(kicad_pcb
	(version 20260206)
	(generator "pcbnew")
	(generator_version "10.0")
	(general
		(thickness 1.6)
		(legacy_teardrops no)
	)
	(paper "A4")
	(title_block
		(title "04192023_DAF0TMB3IC0_F0TG_MB_C_brd_V02_OCP.brd")
		(comment 1 "Grand Teton / footprints 3329-3334 of 8354")
	)
	(layers
		(0 "F.Cu" signal "TOP")
		(4 "In1.Cu" signal "GND")
		(6 "In2.Cu" signal "IN1")
		(8 "In3.Cu" signal "GND1")
		(10 "In4.Cu" signal "IN2")
		(12 "In5.Cu" signal "GND2")
		(14 "In6.Cu" signal "IN3")
		(16 "In7.Cu" signal "GND3")
		(18 "In8.Cu" signal "VCC")
		(20 "In9.Cu" signal "VCC1")
		(22 "In10.Cu" signal "GND4")
		(24 "In11.Cu" signal "IN4")
		(26 "In12.Cu" signal "GND5")
		(28 "In13.Cu" signal "IN5")
		(30 "In14.Cu" signal "GND6")
		(32 "In15.Cu" signal "IN6")
		(34 "In16.Cu" signal "GND7")
		(2 "B.Cu" signal "BOTTOM")
		(9 "F.Adhes" user "F.Adhesive")
		(11 "B.Adhes" user "B.Adhesive")
		(13 "F.Paste" user "Package Geometry/Pastemask Top")
		(15 "B.Paste" user "Package Geometry/Pastemask Bottom")
		(5 "F.SilkS" user "Ref Des/Silkscreen Top")
		(7 "B.SilkS" user "Ref Des/Silkscreen Bottom")
		(1 "F.Mask" user "Board Geometry/Soldermask Top")
		(3 "B.Mask" user "Board Geometry/Soldermask Bottom")
		(17 "Dwgs.User" user "User.Drawings")
		(19 "Cmts.User" user "User.Comments")
		(21 "Eco1.User" user "User.Eco1")
		(23 "Eco2.User" user "User.Eco2")
		(25 "Edge.Cuts" user "Board Geometry/Outline")
		(27 "Margin" user)
		(31 "F.CrtYd" user "Package Geometry/Place Bound Top")
		(29 "B.CrtYd" user "Package Geometry/Place Bound Bottom")
		(35 "F.Fab" user "Ref Des/Assembly Top")
		(33 "B.Fab" user "Ref Des/Assembly Bottom")
	)
	(footprint ""
		(layer "F.Cu")
		(at 429.299116 -109.26699 -90)
		(property "Reference" "PR3789"
			(at 0 0 270)
			(layer "F.SilkS")
			(hide yes)
			(effects
				(font
					(size 1.27 1.27)
				)
			)
		)
		(property "Value" ""
			(at 0 0 270)
			(layer "F.Fab")
			(effects
				(font
					(size 1.27 1.27)
				)
			)
		)
		(duplicate_pad_numbers_are_jumpers no)
		(fp_line
			(start -0.7874 0.4064)
			(end -0.7874 -0.4064)
			(stroke
				(width 0.1524)
				(type default)
			)
			(layer "F.SilkS")
		)
		(fp_line
			(start 0.7874 0.4064)
			(end -0.7874 0.4064)
			(stroke
				(width 0.1524)
				(type default)
			)
			(layer "F.SilkS")
		)
		(fp_line
			(start -0.7874 -0.4064)
			(end 0.7874 -0.4064)
			(stroke
				(width 0.1524)
				(type default)
			)
			(layer "F.SilkS")
		)
		(fp_line
			(start 0.7874 -0.4064)
			(end 0.7874 0.4064)
			(stroke
				(width 0.1524)
				(type default)
			)
			(layer "F.SilkS")
		)
		(fp_line
			(start -0.67945 0.3048)
			(end -0.67945 -0.305054)
			(stroke
				(width 0.1)
				(type default)
			)
			(layer "F.Fab")
		)
		(fp_line
			(start -0.12065 0.3048)
			(end -0.67945 0.3048)
			(stroke
				(width 0.1)
				(type default)
			)
			(layer "F.Fab")
		)
		(fp_line
			(start 0.120396 0.3048)
			(end 0.120396 0.2794)
			(stroke
				(width 0.1)
				(type default)
			)
			(layer "F.Fab")
		)
		(fp_line
			(start 0.67945 0.3048)
			(end 0.120396 0.3048)
			(stroke
				(width 0.1)
				(type default)
			)
			(layer "F.Fab")
		)
		(fp_line
			(start -0.12065 0.2794)
			(end -0.12065 0.3048)
			(stroke
				(width 0.1)
				(type default)
			)
			(layer "F.Fab")
		)
		(fp_line
			(start 0.120396 0.2794)
			(end -0.12065 0.2794)
			(stroke
				(width 0.1)
				(type default)
			)
			(layer "F.Fab")
		)
		(fp_line
			(start -0.12065 -0.2794)
			(end 0.12065 -0.2794)
			(stroke
				(width 0.1)
				(type default)
			)
			(layer "F.Fab")
		)
		(fp_line
			(start 0.12065 -0.2794)
			(end 0.12065 -0.3048)
			(stroke
				(width 0.1)
				(type default)
			)
			(layer "F.Fab")
		)
		(fp_line
			(start 0.12065 -0.3048)
			(end 0.67945 -0.3048)
			(stroke
				(width 0.1)
				(type default)
			)
			(layer "F.Fab")
		)
		(fp_line
			(start 0.67945 -0.3048)
			(end 0.67945 0.3048)
			(stroke
				(width 0.1)
				(type default)
			)
			(layer "F.Fab")
		)
		(fp_line
			(start -0.67945 -0.305054)
			(end -0.12065 -0.305054)
			(stroke
				(width 0.1)
				(type default)
			)
			(layer "F.Fab")
		)
		(fp_line
			(start -0.12065 -0.305054)
			(end -0.12065 -0.2794)
			(stroke
				(width 0.1)
				(type default)
			)
			(layer "F.Fab")
		)
		(pad "1" smd circle
			(at -0.40005 0 270)
			(size 0 0)
			(layers "F.Cu" "F.Mask" "F.Paste")
			(net "P3V3_AUX")
		)
		(pad "2" smd circle
			(at 0.40005 0 270)
			(size 0 0)
			(layers "F.Cu" "F.Mask" "F.Paste")
			(net "P3V3_OCP_UV_1")
		)
	)
	(footprint ""
		(layer "F.Cu")
		(at 212.993732 -111.646208 180)
		(property "Reference" "R134"
			(at 0 0 180)
			(layer "F.SilkS")
			(hide yes)
			(effects
				(font
					(size 1.27 1.27)
				)
			)
		)
		(property "Value" ""
			(at 0 0 180)
			(layer "F.Fab")
			(effects
				(font
					(size 1.27 1.27)
				)
			)
		)
		(duplicate_pad_numbers_are_jumpers no)
		(fp_line
			(start 0.7874 0.4064)
			(end -0.7874 0.4064)
			(stroke
				(width 0.1524)
				(type default)
			)
			(layer "F.SilkS")
		)
		(fp_line
			(start 0.7874 -0.4064)
			(end 0.7874 0.4064)
			(stroke
				(width 0.1524)
				(type default)
			)
			(layer "F.SilkS")
		)
		(fp_line
			(start -0.7874 0.4064)
			(end -0.7874 -0.4064)
			(stroke
				(width 0.1524)
				(type default)
			)
			(layer "F.SilkS")
		)
		(fp_line
			(start -0.7874 -0.4064)
			(end 0.7874 -0.4064)
			(stroke
				(width 0.1524)
				(type default)
			)
			(layer "F.SilkS")
		)
		(fp_line
			(start 0.67945 0.3048)
			(end 0.120396 0.3048)
			(stroke
				(width 0.1)
				(type default)
			)
			(layer "F.Fab")
		)
		(fp_line
			(start 0.67945 -0.3048)
			(end 0.67945 0.3048)
			(stroke
				(width 0.1)
				(type default)
			)
			(layer "F.Fab")
		)
		(fp_line
			(start 0.12065 -0.2794)
			(end 0.12065 -0.3048)
			(stroke
				(width 0.1)
				(type default)
			)
			(layer "F.Fab")
		)
		(fp_line
			(start 0.12065 -0.3048)
			(end 0.67945 -0.3048)
			(stroke
				(width 0.1)
				(type default)
			)
			(layer "F.Fab")
		)
		(fp_line
			(start 0.120396 0.3048)
			(end 0.120396 0.2794)
			(stroke
				(width 0.1)
				(type default)
			)
			(layer "F.Fab")
		)
		(fp_line
			(start 0.120396 0.2794)
			(end -0.12065 0.2794)
			(stroke
				(width 0.1)
				(type default)
			)
			(layer "F.Fab")
		)
		(fp_line
			(start -0.12065 0.3048)
			(end -0.67945 0.3048)
			(stroke
				(width 0.1)
				(type default)
			)
			(layer "F.Fab")
		)
		(fp_line
			(start -0.12065 0.2794)
			(end -0.12065 0.3048)
			(stroke
				(width 0.1)
				(type default)
			)
			(layer "F.Fab")
		)
		(fp_line
			(start -0.12065 -0.2794)
			(end 0.12065 -0.2794)
			(stroke
				(width 0.1)
				(type default)
			)
			(layer "F.Fab")
		)
		(fp_line
			(start -0.12065 -0.305054)
			(end -0.12065 -0.2794)
			(stroke
				(width 0.1)
				(type default)
			)
			(layer "F.Fab")
		)
		(fp_line
			(start -0.67945 0.3048)
			(end -0.67945 -0.305054)
			(stroke
				(width 0.1)
				(type default)
			)
			(layer "F.Fab")
		)
		(fp_line
			(start -0.67945 -0.305054)
			(end -0.12065 -0.305054)
			(stroke
				(width 0.1)
				(type default)
			)
			(layer "F.Fab")
		)
		(pad "1" smd circle
			(at -0.40005 0 180)
			(size 0 0)
			(layers "F.Cu" "F.Mask" "F.Paste")
			(net "FM_APML_MUX2_OE_N")
		)
		(pad "2" smd circle
			(at 0.40005 0 180)
			(size 0 0)
			(layers "F.Cu" "F.Mask" "F.Paste")
			(net "P3V3_AUX")
		)
	)
	(footprint ""
		(layer "F.Cu")
		(at 9.74471 -70.560692)
		(property "Reference" "R3136"
			(at 0 0 0)
			(layer "F.SilkS")
			(hide yes)
			(effects
				(font
					(size 1.27 1.27)
				)
			)
		)
		(property "Value" ""
			(at 0 0 0)
			(layer "F.Fab")
			(effects
				(font
					(size 1.27 1.27)
				)
			)
		)
		(duplicate_pad_numbers_are_jumpers no)
		(fp_line
			(start -0.7874 -0.4064)
			(end 0.7874 -0.4064)
			(stroke
				(width 0.1524)
				(type default)
			)
			(layer "F.SilkS")
		)
		(fp_line
			(start -0.7874 0.4064)
			(end -0.7874 -0.4064)
			(stroke
				(width 0.1524)
				(type default)
			)
			(layer "F.SilkS")
		)
		(fp_line
			(start 0.7874 -0.4064)
			(end 0.7874 0.4064)
			(stroke
				(width 0.1524)
				(type default)
			)
			(layer "F.SilkS")
		)
		(fp_line
			(start 0.7874 0.4064)
			(end -0.7874 0.4064)
			(stroke
				(width 0.1524)
				(type default)
			)
			(layer "F.SilkS")
		)
		(fp_line
			(start -0.67945 -0.305054)
			(end -0.12065 -0.305054)
			(stroke
				(width 0.1)
				(type default)
			)
			(layer "F.Fab")
		)
		(fp_line
			(start -0.67945 0.3048)
			(end -0.67945 -0.305054)
			(stroke
				(width 0.1)
				(type default)
			)
			(layer "F.Fab")
		)
		(fp_line
			(start -0.12065 -0.305054)
			(end -0.12065 -0.2794)
			(stroke
				(width 0.1)
				(type default)
			)
			(layer "F.Fab")
		)
		(fp_line
			(start -0.12065 -0.2794)
			(end 0.12065 -0.2794)
			(stroke
				(width 0.1)
				(type default)
			)
			(layer "F.Fab")
		)
		(fp_line
			(start -0.12065 0.2794)
			(end -0.12065 0.3048)
			(stroke
				(width 0.1)
				(type default)
			)
			(layer "F.Fab")
		)
		(fp_line
			(start -0.12065 0.3048)
			(end -0.67945 0.3048)
			(stroke
				(width 0.1)
				(type default)
			)
			(layer "F.Fab")
		)
		(fp_line
			(start 0.120396 0.2794)
			(end -0.12065 0.2794)
			(stroke
				(width 0.1)
				(type default)
			)
			(layer "F.Fab")
		)
		(fp_line
			(start 0.120396 0.3048)
			(end 0.120396 0.2794)
			(stroke
				(width 0.1)
				(type default)
			)
			(layer "F.Fab")
		)
		(fp_line
			(start 0.12065 -0.3048)
			(end 0.67945 -0.3048)
			(stroke
				(width 0.1)
				(type default)
			)
			(layer "F.Fab")
		)
		(fp_line
			(start 0.12065 -0.2794)
			(end 0.12065 -0.3048)
			(stroke
				(width 0.1)
				(type default)
			)
			(layer "F.Fab")
		)
		(fp_line
			(start 0.67945 -0.3048)
			(end 0.67945 0.3048)
			(stroke
				(width 0.1)
				(type default)
			)
			(layer "F.Fab")
		)
		(fp_line
			(start 0.67945 0.3048)
			(end 0.120396 0.3048)
			(stroke
				(width 0.1)
				(type default)
			)
			(layer "F.Fab")
		)
		(pad "1" smd circle
			(at -0.40005 0)
			(size 0 0)
			(layers "F.Cu" "F.Mask" "F.Paste")
			(net "P3V3_AUX")
		)
		(pad "2" smd circle
			(at 0.40005 0)
			(size 0 0)
			(layers "F.Cu" "F.Mask" "F.Paste")
			(net "OCP_V3_2_PRSNT3_R_N")
		)
	)
	(footprint ""
		(layer "F.Cu")
		(at 208.894426 -112.662208 180)
		(property "Reference" "R5099"
			(at 0 0 180)
			(layer "F.SilkS")
			(hide yes)
			(effects
				(font
					(size 1.27 1.27)
				)
			)
		)
		(property "Value" ""
			(at 0 0 180)
			(layer "F.Fab")
			(effects
				(font
					(size 1.27 1.27)
				)
			)
		)
		(duplicate_pad_numbers_are_jumpers no)
		(fp_line
			(start 0.7874 0.4064)
			(end -0.7874 0.4064)
			(stroke
				(width 0.1524)
				(type default)
			)
			(layer "F.SilkS")
		)
		(fp_line
			(start 0.7874 -0.4064)
			(end 0.7874 0.4064)
			(stroke
				(width 0.1524)
				(type default)
			)
			(layer "F.SilkS")
		)
		(fp_line
			(start -0.7874 0.4064)
			(end -0.7874 -0.4064)
			(stroke
				(width 0.1524)
				(type default)
			)
			(layer "F.SilkS")
		)
		(fp_line
			(start -0.7874 -0.4064)
			(end 0.7874 -0.4064)
			(stroke
				(width 0.1524)
				(type default)
			)
			(layer "F.SilkS")
		)
		(fp_line
			(start 0.67945 0.3048)
			(end 0.120396 0.3048)
			(stroke
				(width 0.1)
				(type default)
			)
			(layer "F.Fab")
		)
		(fp_line
			(start 0.67945 -0.3048)
			(end 0.67945 0.3048)
			(stroke
				(width 0.1)
				(type default)
			)
			(layer "F.Fab")
		)
		(fp_line
			(start 0.12065 -0.2794)
			(end 0.12065 -0.3048)
			(stroke
				(width 0.1)
				(type default)
			)
			(layer "F.Fab")
		)
		(fp_line
			(start 0.12065 -0.3048)
			(end 0.67945 -0.3048)
			(stroke
				(width 0.1)
				(type default)
			)
			(layer "F.Fab")
		)
		(fp_line
			(start 0.120396 0.3048)
			(end 0.120396 0.2794)
			(stroke
				(width 0.1)
				(type default)
			)
			(layer "F.Fab")
		)
		(fp_line
			(start 0.120396 0.2794)
			(end -0.12065 0.2794)
			(stroke
				(width 0.1)
				(type default)
			)
			(layer "F.Fab")
		)
		(fp_line
			(start -0.12065 0.3048)
			(end -0.67945 0.3048)
			(stroke
				(width 0.1)
				(type default)
			)
			(layer "F.Fab")
		)
		(fp_line
			(start -0.12065 0.2794)
			(end -0.12065 0.3048)
			(stroke
				(width 0.1)
				(type default)
			)
			(layer "F.Fab")
		)
		(fp_line
			(start -0.12065 -0.2794)
			(end 0.12065 -0.2794)
			(stroke
				(width 0.1)
				(type default)
			)
			(layer "F.Fab")
		)
		(fp_line
			(start -0.12065 -0.305054)
			(end -0.12065 -0.2794)
			(stroke
				(width 0.1)
				(type default)
			)
			(layer "F.Fab")
		)
		(fp_line
			(start -0.67945 0.3048)
			(end -0.67945 -0.305054)
			(stroke
				(width 0.1)
				(type default)
			)
			(layer "F.Fab")
		)
		(fp_line
			(start -0.67945 -0.305054)
			(end -0.12065 -0.305054)
			(stroke
				(width 0.1)
				(type default)
			)
			(layer "F.Fab")
		)
		(pad "1" smd circle
			(at -0.40005 0 180)
			(size 0 0)
			(layers "F.Cu" "F.Mask" "F.Paste")
			(net "FPGA_DEBUG_SW_SPARE")
		)
		(pad "2" smd circle
			(at 0.40005 0 180)
			(size 0 0)
			(layers "F.Cu" "F.Mask" "F.Paste")
			(net "FM_FPGA_DEBUG_SW_SPARE")
		)
	)
	(footprint ""
		(layer "F.Cu")
		(at 331.662532 -141.36243)
		(property "Reference" "PR417"
			(at 0 0 0)
			(layer "F.SilkS")
			(hide yes)
			(effects
				(font
					(size 1.27 1.27)
				)
			)
		)
		(property "Value" ""
			(at 0 0 0)
			(layer "F.Fab")
			(effects
				(font
					(size 1.27 1.27)
				)
			)
		)
		(duplicate_pad_numbers_are_jumpers no)
		(fp_line
			(start -0.7874 -0.4064)
			(end 0.7874 -0.4064)
			(stroke
				(width 0.1524)
				(type default)
			)
			(layer "F.SilkS")
		)
		(fp_line
			(start -0.7874 0.4064)
			(end -0.7874 -0.4064)
			(stroke
				(width 0.1524)
				(type default)
			)
			(layer "F.SilkS")
		)
		(fp_line
			(start 0.7874 -0.4064)
			(end 0.7874 0.4064)
			(stroke
				(width 0.1524)
				(type default)
			)
			(layer "F.SilkS")
		)
		(fp_line
			(start 0.7874 0.4064)
			(end -0.7874 0.4064)
			(stroke
				(width 0.1524)
				(type default)
			)
			(layer "F.SilkS")
		)
		(fp_line
			(start -0.67945 -0.305054)
			(end -0.12065 -0.305054)
			(stroke
				(width 0.1)
				(type default)
			)
			(layer "F.Fab")
		)
		(fp_line
			(start -0.67945 0.3048)
			(end -0.67945 -0.305054)
			(stroke
				(width 0.1)
				(type default)
			)
			(layer "F.Fab")
		)
		(fp_line
			(start -0.12065 -0.305054)
			(end -0.12065 -0.2794)
			(stroke
				(width 0.1)
				(type default)
			)
			(layer "F.Fab")
		)
		(fp_line
			(start -0.12065 -0.2794)
			(end 0.12065 -0.2794)
			(stroke
				(width 0.1)
				(type default)
			)
			(layer "F.Fab")
		)
		(fp_line
			(start -0.12065 0.2794)
			(end -0.12065 0.3048)
			(stroke
				(width 0.1)
				(type default)
			)
			(layer "F.Fab")
		)
		(fp_line
			(start -0.12065 0.3048)
			(end -0.67945 0.3048)
			(stroke
				(width 0.1)
				(type default)
			)
			(layer "F.Fab")
		)
		(fp_line
			(start 0.120396 0.2794)
			(end -0.12065 0.2794)
			(stroke
				(width 0.1)
				(type default)
			)
			(layer "F.Fab")
		)
		(fp_line
			(start 0.120396 0.3048)
			(end 0.120396 0.2794)
			(stroke
				(width 0.1)
				(type default)
			)
			(layer "F.Fab")
		)
		(fp_line
			(start 0.12065 -0.3048)
			(end 0.67945 -0.3048)
			(stroke
				(width 0.1)
				(type default)
			)
			(layer "F.Fab")
		)
		(fp_line
			(start 0.12065 -0.2794)
			(end 0.12065 -0.3048)
			(stroke
				(width 0.1)
				(type default)
			)
			(layer "F.Fab")
		)
		(fp_line
			(start 0.67945 -0.3048)
			(end 0.67945 0.3048)
			(stroke
				(width 0.1)
				(type default)
			)
			(layer "F.Fab")
		)
		(fp_line
			(start 0.67945 0.3048)
			(end 0.120396 0.3048)
			(stroke
				(width 0.1)
				(type default)
			)
			(layer "F.Fab")
		)
		(pad "1" smd circle
			(at -0.40005 0)
			(size 0 0)
			(layers "F.Cu" "F.Mask" "F.Paste")
			(net "GND")
		)
		(pad "2" smd circle
			(at 0.40005 0)
			(size 0 0)
			(layers "F.Cu" "F.Mask" "F.Paste")
			(net "PVDD18_S5_P0_MODE")
		)
	)
	(footprint ""
		(layer "F.Cu")
		(at 101.948234 -141.20241 180)
		(property "Reference" "PR181"
			(at 0 0 180)
			(layer "F.SilkS")
			(hide yes)
			(effects
				(font
					(size 1.27 1.27)
				)
			)
		)
		(property "Value" ""
			(at 0 0 180)
			(layer "F.Fab")
			(effects
				(font
					(size 1.27 1.27)
				)
			)
		)
		(duplicate_pad_numbers_are_jumpers no)
		(fp_line
			(start 0.7874 0.4064)
			(end -0.7874 0.4064)
			(stroke
				(width 0.1524)
				(type default)
			)
			(layer "F.SilkS")
		)
		(fp_line
			(start 0.7874 -0.4064)
			(end 0.7874 0.4064)
			(stroke
				(width 0.1524)
				(type default)
			)
			(layer "F.SilkS")
		)
		(fp_line
			(start -0.7874 0.4064)
			(end -0.7874 -0.4064)
			(stroke
				(width 0.1524)
				(type default)
			)
			(layer "F.SilkS")
		)
		(fp_line
			(start -0.7874 -0.4064)
			(end 0.7874 -0.4064)
			(stroke
				(width 0.1524)
				(type default)
			)
			(layer "F.SilkS")
		)
		(fp_line
			(start 0.67945 0.3048)
			(end 0.120396 0.3048)
			(stroke
				(width 0.1)
				(type default)
			)
			(layer "F.Fab")
		)
		(fp_line
			(start 0.67945 -0.3048)
			(end 0.67945 0.3048)
			(stroke
				(width 0.1)
				(type default)
			)
			(layer "F.Fab")
		)
		(fp_line
			(start 0.12065 -0.2794)
			(end 0.12065 -0.3048)
			(stroke
				(width 0.1)
				(type default)
			)
			(layer "F.Fab")
		)
		(fp_line
			(start 0.12065 -0.3048)
			(end 0.67945 -0.3048)
			(stroke
				(width 0.1)
				(type default)
			)
			(layer "F.Fab")
		)
		(fp_line
			(start 0.120396 0.3048)
			(end 0.120396 0.2794)
			(stroke
				(width 0.1)
				(type default)
			)
			(layer "F.Fab")
		)
		(fp_line
			(start 0.120396 0.2794)
			(end -0.12065 0.2794)
			(stroke
				(width 0.1)
				(type default)
			)
			(layer "F.Fab")
		)
		(fp_line
			(start -0.12065 0.3048)
			(end -0.67945 0.3048)
			(stroke
				(width 0.1)
				(type default)
			)
			(layer "F.Fab")
		)
		(fp_line
			(start -0.12065 0.2794)
			(end -0.12065 0.3048)
			(stroke
				(width 0.1)
				(type default)
			)
			(layer "F.Fab")
		)
		(fp_line
			(start -0.12065 -0.2794)
			(end 0.12065 -0.2794)
			(stroke
				(width 0.1)
				(type default)
			)
			(layer "F.Fab")
		)
		(fp_line
			(start -0.12065 -0.305054)
			(end -0.12065 -0.2794)
			(stroke
				(width 0.1)
				(type default)
			)
			(layer "F.Fab")
		)
		(fp_line
			(start -0.67945 0.3048)
			(end -0.67945 -0.305054)
			(stroke
				(width 0.1)
				(type default)
			)
			(layer "F.Fab")
		)
		(fp_line
			(start -0.67945 -0.305054)
			(end -0.12065 -0.305054)
			(stroke
				(width 0.1)
				(type default)
			)
			(layer "F.Fab")
		)
		(pad "1" smd circle
			(at -0.40005 0 180)
			(size 0 0)
			(layers "F.Cu" "F.Mask" "F.Paste")
			(net "P12V_AUX")
		)
		(pad "2" smd circle
			(at 0.40005 0 180)
			(size 0 0)
			(layers "F.Cu" "F.Mask" "F.Paste")
			(net "PVDDCR_CPU0_P1_VINSEN")
		)
	)
)
